# S9S_MB_2U (Grand Teton) — schematic netlist excerpt (pin names and nets, part order shuffled) for the footprints in the layout excerpt that follows; sources: Cadence DE-HDL packaged netlist, KiCad conversion of 03242023_DA0F0TMBIJ0_F0T_Motherboard_J_brd_V01_OCP.brd

PR3970  Q_RES  2.67K 1% EMPTY  pkg 0402LF  page 192 : A = P12V_E1S_SENSE_0 ; B = GND
R4708  Q_RES  0 5% EMPTY  pkg 0402LF  page 242 : A = P12V_SCM_FAULT_N ; B = P12V_SCM_FAULT_R_N

(kicad_pcb
	(version 20260206)
	(generator "pcbnew")
	(generator_version "10.0")
	(general
		(thickness 1.6)
		(legacy_teardrops no)
	)
	(paper "A4")
	(title_block
		(title "03242023_DA0F0TMBIJ0_F0T_Motherboard_J_brd_V01_OCP.brd")
		(comment 1 "Grand Teton / footprints 1416-1417 of 6105")
	)
	(layers
		(0 "F.Cu" signal "TOP")
		(4 "In1.Cu" signal "GND")
		(6 "In2.Cu" signal "IN1")
		(8 "In3.Cu" signal "GND1")
		(10 "In4.Cu" signal "IN2")
		(12 "In5.Cu" signal "GND2")
		(14 "In6.Cu" signal "IN3")
		(16 "In7.Cu" signal "GND3")
		(18 "In8.Cu" signal "VCC")
		(20 "In9.Cu" signal "VCC1")
		(22 "In10.Cu" signal "GND4")
		(24 "In11.Cu" signal "IN4")
		(26 "In12.Cu" signal "GND5")
		(28 "In13.Cu" signal "IN5")
		(30 "In14.Cu" signal "GND6")
		(32 "In15.Cu" signal "IN6")
		(34 "In16.Cu" signal "GND7")
		(2 "B.Cu" signal "BOTTOM")
		(9 "F.Adhes" user "F.Adhesive")
		(11 "B.Adhes" user "B.Adhesive")
		(13 "F.Paste" user "Package Geometry/Pastemask Top")
		(15 "B.Paste" user "Package Geometry/Pastemask Bottom")
		(5 "F.SilkS" user "Ref Des/Silkscreen Top")
		(7 "B.SilkS" user "Ref Des/Silkscreen Bottom")
		(1 "F.Mask" user "Board Geometry/Soldermask Top")
		(3 "B.Mask" user "Board Geometry/Soldermask Bottom")
		(17 "Dwgs.User" user "User.Drawings")
		(19 "Cmts.User" user "User.Comments")
		(21 "Eco1.User" user "User.Eco1")
		(23 "Eco2.User" user "User.Eco2")
		(25 "Edge.Cuts" user "Board Geometry/Outline")
		(27 "Margin" user)
		(31 "F.CrtYd" user "Package Geometry/Place Bound Top")
		(29 "B.CrtYd" user "Package Geometry/Place Bound Bottom")
		(35 "F.Fab" user "Ref Des/Assembly Top")
		(33 "B.Fab" user "Ref Des/Assembly Bottom")
	)
	(footprint ""
		(layer "F.Cu")
		(at 194.08902 -29.12872 -90)
		(property "Reference" "R4708"
			(at 0 0 270)
			(layer "F.SilkS")
			(hide yes)
			(effects
				(font
					(size 1.27 1.27)
				)
			)
		)
		(property "Value" ""
			(at 0 0 270)
			(layer "F.Fab")
			(effects
				(font
					(size 1.27 1.27)
				)
			)
		)
		(duplicate_pad_numbers_are_jumpers no)
		(fp_line
			(start -0.7874 0.4064)
			(end -0.7874 -0.4064)
			(stroke
				(width 0.1524)
				(type default)
			)
			(layer "F.SilkS")
		)
		(fp_line
			(start 0.7874 0.4064)
			(end -0.7874 0.4064)
			(stroke
				(width 0.1524)
				(type default)
			)
			(layer "F.SilkS")
		)
		(fp_line
			(start -0.7874 -0.4064)
			(end 0.7874 -0.4064)
			(stroke
				(width 0.1524)
				(type default)
			)
			(layer "F.SilkS")
		)
		(fp_line
			(start 0.7874 -0.4064)
			(end 0.7874 0.4064)
			(stroke
				(width 0.1524)
				(type default)
			)
			(layer "F.SilkS")
		)
		(fp_line
			(start -0.67945 0.3048)
			(end -0.67945 -0.305054)
			(stroke
				(width 0.1)
				(type default)
			)
			(layer "F.Fab")
		)
		(fp_line
			(start -0.12065 0.3048)
			(end -0.67945 0.3048)
			(stroke
				(width 0.1)
				(type default)
			)
			(layer "F.Fab")
		)
		(fp_line
			(start 0.120396 0.3048)
			(end 0.120396 0.2794)
			(stroke
				(width 0.1)
				(type default)
			)
			(layer "F.Fab")
		)
		(fp_line
			(start 0.67945 0.3048)
			(end 0.120396 0.3048)
			(stroke
				(width 0.1)
				(type default)
			)
			(layer "F.Fab")
		)
		(fp_line
			(start -0.12065 0.2794)
			(end -0.12065 0.3048)
			(stroke
				(width 0.1)
				(type default)
			)
			(layer "F.Fab")
		)
		(fp_line
			(start 0.120396 0.2794)
			(end -0.12065 0.2794)
			(stroke
				(width 0.1)
				(type default)
			)
			(layer "F.Fab")
		)
		(fp_line
			(start -0.12065 -0.2794)
			(end 0.12065 -0.2794)
			(stroke
				(width 0.1)
				(type default)
			)
			(layer "F.Fab")
		)
		(fp_line
			(start 0.12065 -0.2794)
			(end 0.12065 -0.3048)
			(stroke
				(width 0.1)
				(type default)
			)
			(layer "F.Fab")
		)
		(fp_line
			(start 0.12065 -0.3048)
			(end 0.67945 -0.3048)
			(stroke
				(width 0.1)
				(type default)
			)
			(layer "F.Fab")
		)
		(fp_line
			(start 0.67945 -0.3048)
			(end 0.67945 0.3048)
			(stroke
				(width 0.1)
				(type default)
			)
			(layer "F.Fab")
		)
		(fp_line
			(start -0.67945 -0.305054)
			(end -0.12065 -0.305054)
			(stroke
				(width 0.1)
				(type default)
			)
			(layer "F.Fab")
		)
		(fp_line
			(start -0.12065 -0.305054)
			(end -0.12065 -0.2794)
			(stroke
				(width 0.1)
				(type default)
			)
			(layer "F.Fab")
		)
		(pad "1" smd circle
			(at -0.40005 0 270)
			(size 0 0)
			(layers "F.Cu" "F.Mask" "F.Paste")
			(net "P12V_SCM_FAULT_N")
		)
		(pad "2" smd circle
			(at 0.40005 0 270)
			(size 0 0)
			(layers "F.Cu" "F.Mask" "F.Paste")
			(net "P12V_SCM_FAULT_R_N")
		)
	)
	(footprint ""
		(layer "F.Cu")
		(at 253.97841 -44.849542 90)
		(property "Reference" "PR3970"
			(at 0 0 90)
			(layer "F.SilkS")
			(hide yes)
			(effects
				(font
					(size 1.27 1.27)
				)
			)
		)
		(property "Value" ""
			(at 0 0 90)
			(layer "F.Fab")
			(effects
				(font
					(size 1.27 1.27)
				)
			)
		)
		(duplicate_pad_numbers_are_jumpers no)
		(fp_line
			(start 0.7874 -0.4064)
			(end 0.7874 0.4064)
			(stroke
				(width 0.1524)
				(type default)
			)
			(layer "F.SilkS")
		)
		(fp_line
			(start -0.7874 -0.4064)
			(end 0.7874 -0.4064)
			(stroke
				(width 0.1524)
				(type default)
			)
			(layer "F.SilkS")
		)
		(fp_line
			(start 0.7874 0.4064)
			(end -0.7874 0.4064)
			(stroke
				(width 0.1524)
				(type default)
			)
			(layer "F.SilkS")
		)
		(fp_line
			(start -0.7874 0.4064)
			(end -0.7874 -0.4064)
			(stroke
				(width 0.1524)
				(type default)
			)
			(layer "F.SilkS")
		)
		(fp_line
			(start -0.12065 -0.305054)
			(end -0.12065 -0.2794)
			(stroke
				(width 0.1)
				(type default)
			)
			(layer "F.Fab")
		)
		(fp_line
			(start -0.67945 -0.305054)
			(end -0.12065 -0.305054)
			(stroke
				(width 0.1)
				(type default)
			)
			(layer "F.Fab")
		)
		(fp_line
			(start 0.67945 -0.3048)
			(end 0.67945 0.3048)
			(stroke
				(width 0.1)
				(type default)
			)
			(layer "F.Fab")
		)
		(fp_line
			(start 0.12065 -0.3048)
			(end 0.67945 -0.3048)
			(stroke
				(width 0.1)
				(type default)
			)
			(layer "F.Fab")
		)
		(fp_line
			(start 0.12065 -0.2794)
			(end 0.12065 -0.3048)
			(stroke
				(width 0.1)
				(type default)
			)
			(layer "F.Fab")
		)
		(fp_line
			(start -0.12065 -0.2794)
			(end 0.12065 -0.2794)
			(stroke
				(width 0.1)
				(type default)
			)
			(layer "F.Fab")
		)
		(fp_line
			(start 0.120396 0.2794)
			(end -0.12065 0.2794)
			(stroke
				(width 0.1)
				(type default)
			)
			(layer "F.Fab")
		)
		(fp_line
			(start -0.12065 0.2794)
			(end -0.12065 0.3048)
			(stroke
				(width 0.1)
				(type default)
			)
			(layer "F.Fab")
		)
		(fp_line
			(start 0.67945 0.3048)
			(end 0.120396 0.3048)
			(stroke
				(width 0.1)
				(type default)
			)
			(layer "F.Fab")
		)
		(fp_line
			(start 0.120396 0.3048)
			(end 0.120396 0.2794)
			(stroke
				(width 0.1)
				(type default)
			)
			(layer "F.Fab")
		)
		(fp_line
			(start -0.12065 0.3048)
			(end -0.67945 0.3048)
			(stroke
				(width 0.1)
				(type default)
			)
			(layer "F.Fab")
		)
		(fp_line
			(start -0.67945 0.3048)
			(end -0.67945 -0.305054)
			(stroke
				(width 0.1)
				(type default)
			)
			(layer "F.Fab")
		)
		(pad "1" smd circle
			(at -0.40005 0 90)
			(size 0 0)
			(layers "F.Cu" "F.Mask" "F.Paste")
			(net "P12V_E1S_SENSE_0")
		)
		(pad "2" smd circle
			(at 0.40005 0 90)
			(size 0 0)
			(layers "F.Cu" "F.Mask" "F.Paste")
			(net "GND")
		)
	)
)
